# TIMECARD (Time Appliance Project (Time Card)) — schematic netlist excerpt (pin names and nets, part order shuffled) for the footprints in the layout excerpt that follows; sources: Cadence DE-HDL packaged netlist, KiCad conversion of R4006-B0001-02_R01.brd

R92  RESISTOR  100OHM 1%  pkg SMC_0402R_H016  page 21 : \1\ = R_MAC_10MHZ_RF_OUT ; \2\ = FPGA_IN_MAC_10MHZ_OUT
C246  CAPACITOR  10UF 6.3V 20%  pkg SMC_0402R_H022  page 15 : \1\ = VDD3V3_OSC_200M ; \2\ = SG

(kicad_pcb
	(version 20260206)
	(generator "pcbnew")
	(generator_version "10.0")
	(general
		(thickness 1.6)
		(legacy_teardrops no)
	)
	(paper "A4")
	(title_block
		(title "timecard-production-celestica-r4006 — R4006-B0001-02_R01.brd")
		(comment 1 "Time Appliance Project (Time Card) / footprints 813-814 of 1113")
	)
	(layers
		(0 "F.Cu" signal "TOP")
		(4 "In1.Cu" signal "L02_GND1")
		(6 "In2.Cu" signal "L03_SIG1")
		(8 "In3.Cu" signal "L04_GND2")
		(10 "In4.Cu" signal "L05_VCC1")
		(12 "In5.Cu" signal "L06_VCC2")
		(14 "In6.Cu" signal "L07_GND3")
		(16 "In7.Cu" signal "L08_SIG2")
		(18 "In8.Cu" signal "L09_GND4")
		(2 "B.Cu" signal "BOTTOM")
		(9 "F.Adhes" user "F.Adhesive")
		(11 "B.Adhes" user "B.Adhesive")
		(13 "F.Paste" user "Package Geometry/Pastemask Top")
		(15 "B.Paste" user "Package Geometry/Pastemask Bottom")
		(5 "F.SilkS" user "Ref Des/Silkscreen Top")
		(7 "B.SilkS" user "Ref Des/Silkscreen Bottom")
		(1 "F.Mask" user "Board Geometry/Soldermask Top")
		(3 "B.Mask" user "Board Geometry/Soldermask Bottom")
		(17 "Dwgs.User" user "User.Drawings")
		(19 "Cmts.User" user "User.Comments")
		(21 "Eco1.User" user "User.Eco1")
		(23 "Eco2.User" user "User.Eco2")
		(25 "Edge.Cuts" user "Board Geometry/Outline")
		(27 "Margin" user)
		(31 "F.CrtYd" user "Package Geometry/Place Bound Top")
		(29 "B.CrtYd" user "Package Geometry/Place Bound Bottom")
		(35 "F.Fab" user "Ref Des/Assembly Top")
		(33 "B.Fab" user "Ref Des/Assembly Bottom")
	)
	(footprint ""
		(layer "B.Cu")
		(at 108.585 -23.876 -90)
		(property "Reference" "C246"
			(at -0.127 2.96037 270)
			(unlocked yes)
			(layer "B.SilkS")
			(effects
				(font
					(size 0.7874 0.5842)
					(thickness 0.1524)
				)
				(justify mirror)
			)
		)
		(property "Value" "VAL*"
			(at -0.0762 2.067306 270)
			(unlocked yes)
			(layer "B.Fab")
			(hide yes)
			(effects
				(font
					(size 0.7874 0.5842)
					(thickness 0.1524)
				)
				(justify mirror)
			)
		)
		(property "Device Type" "CAPACITOR-G105-0C106-BM,10UF,2A"
			(at -0.0508 1.127506 270)
			(unlocked yes)
			(layer "B.Fab")
			(hide yes)
			(effects
				(font
					(size 0.7874 0.5842)
					(thickness 0.1524)
				)
				(justify mirror)
			)
		)
		(property "User Part Number" "PARTNUM*"
			(at -0.1016 4.023106 270)
			(unlocked yes)
			(layer "Cmts.User")
			(hide yes)
			(effects
				(font
					(size 0.7874 0.5842)
					(thickness 0.1524)
				)
				(justify mirror)
			)
		)
		(property "Tolerance" "TOL*"
			(at -0.0762 3.032506 270)
			(unlocked yes)
			(layer "Cmts.User")
			(hide yes)
			(effects
				(font
					(size 0.7874 0.5842)
					(thickness 0.1524)
				)
				(justify mirror)
			)
		)
		(duplicate_pad_numbers_are_jumpers no)
		(fp_line
			(start -1.143 0.5588)
			(end -1.143 -0.5588)
			(stroke
				(width 0.1)
				(type default)
			)
			(layer "B.SilkS")
		)
		(fp_line
			(start 1.143 0.5588)
			(end -1.143 0.5588)
			(stroke
				(width 0.1)
				(type default)
			)
			(layer "B.SilkS")
		)
		(fp_line
			(start -1.143 -0.5588)
			(end 1.143 -0.5588)
			(stroke
				(width 0.1)
				(type default)
			)
			(layer "B.SilkS")
		)
		(fp_line
			(start 1.143 -0.5588)
			(end 1.143 0.5588)
			(stroke
				(width 0.1)
				(type default)
			)
			(layer "B.SilkS")
		)
		(fp_rect
			(start 1.143 0.5588)
			(end -1.143 -0.5588)
			(stroke
				(width 0)
				(type default)
			)
			(fill no)
			(layer "B.CrtYd")
		)
		(fp_line
			(start -0.508 0.3048)
			(end -0.508 -0.3048)
			(stroke
				(width 0.1)
				(type default)
			)
			(layer "B.Fab")
		)
		(fp_line
			(start 0.508 0.3048)
			(end -0.508 0.3048)
			(stroke
				(width 0.1)
				(type default)
			)
			(layer "B.Fab")
		)
		(fp_line
			(start -0.508 -0.3048)
			(end 0.508 -0.3048)
			(stroke
				(width 0.1)
				(type default)
			)
			(layer "B.Fab")
		)
		(fp_line
			(start 0.508 -0.3048)
			(end 0.508 0.3048)
			(stroke
				(width 0.1)
				(type default)
			)
			(layer "B.Fab")
		)
		(pad "1" smd rect
			(at 0.5334 0 90)
			(size 0.7112 0.6096)
			(layers "B.Cu" "B.Mask" "B.Paste")
			(net "VDD3V3_OSC_200M")
		)
		(pad "2" smd rect
			(at -0.5334 0 90)
			(size 0.7112 0.6096)
			(layers "B.Cu" "B.Mask" "B.Paste")
			(net "SG")
		)
		(zone
			(layer "B.Cu")
			(hatch none 0.5)
			(connect_pads
				(clearance 0)
			)
			(min_thickness 0.25)
			(keepout
				(tracks allowed)
				(vias not_allowed)
				(pads allowed)
				(copperpour not_allowed)
				(footprints allowed)
			)
			(placement
				(enabled no)
				(sheetname "")
			)
			(fill
				(thermal_gap 0.5)
				(thermal_bridge_width 0.5)
				(island_removal_mode 0)
			)
			(polygon
				(pts
					(xy 108.2802 -23.7998) (xy 108.8898 -23.7998) (xy 108.8898 -23.9522) (xy 108.2802 -23.9522)
				)
			)
		)
	)
	(footprint ""
		(layer "B.Cu")
		(at 124.587 -47.117)
		(property "Reference" "R92"
			(at 4.064 0.16637 0)
			(unlocked yes)
			(layer "B.SilkS")
			(effects
				(font
					(size 0.7874 0.5842)
					(thickness 0.1524)
				)
				(justify mirror)
			)
		)
		(property "Value" "VAL*"
			(at -0.02032 2.13233 0)
			(unlocked yes)
			(layer "B.Fab")
			(hide yes)
			(effects
				(font
					(size 0.7874 0.5842)
					(thickness 0.1524)
				)
				(justify mirror)
			)
		)
		(property "Tolerance" "TOL*"
			(at -0.044704 3.05435 0)
			(unlocked yes)
			(layer "Cmts.User")
			(hide yes)
			(effects
				(font
					(size 0.7874 0.5842)
					(thickness 0.1524)
				)
				(justify mirror)
			)
		)
		(property "User Part Number" "PARTNUM*"
			(at -0.02032 4.024884 0)
			(unlocked yes)
			(layer "Cmts.User")
			(hide yes)
			(effects
				(font
					(size 0.7874 0.5842)
					(thickness 0.1524)
				)
				(justify mirror)
			)
		)
		(property "Device Type" "RESISTOR-G155-100R0-J0,0OHM,-"
			(at -0.008382 1.210564 0)
			(unlocked yes)
			(layer "B.Fab")
			(hide yes)
			(effects
				(font
					(size 0.7874 0.5842)
					(thickness 0.1524)
				)
				(justify mirror)
			)
		)
		(duplicate_pad_numbers_are_jumpers no)
		(fp_line
			(start -1.143 -0.5588)
			(end 1.143 -0.5588)
			(stroke
				(width 0.1)
				(type default)
			)
			(layer "B.SilkS")
		)
		(fp_line
			(start -1.143 0.5588)
			(end -1.143 -0.5588)
			(stroke
				(width 0.1)
				(type default)
			)
			(layer "B.SilkS")
		)
		(fp_line
			(start 1.143 -0.5588)
			(end 1.143 0.5588)
			(stroke
				(width 0.1)
				(type default)
			)
			(layer "B.SilkS")
		)
		(fp_line
			(start 1.143 0.5588)
			(end -1.143 0.5588)
			(stroke
				(width 0.1)
				(type default)
			)
			(layer "B.SilkS")
		)
		(fp_poly
			(pts
				(xy 1.143 0.5588) (xy -1.143 0.5588) (xy -1.143 -0.5588) (xy 1.143 -0.5588)
			)
			(stroke
				(width 0)
				(type default)
			)
			(fill no)
			(layer "B.CrtYd")
		)
		(fp_line
			(start -0.508 -0.3048)
			(end 0.508 -0.3048)
			(stroke
				(width 0.1)
				(type default)
			)
			(layer "B.Fab")
		)
		(fp_line
			(start -0.508 0.3048)
			(end -0.508 -0.3048)
			(stroke
				(width 0.1)
				(type default)
			)
			(layer "B.Fab")
		)
		(fp_line
			(start 0.508 -0.3048)
			(end 0.508 0.3048)
			(stroke
				(width 0.1)
				(type default)
			)
			(layer "B.Fab")
		)
		(fp_line
			(start 0.508 0.3048)
			(end -0.508 0.3048)
			(stroke
				(width 0.1)
				(type default)
			)
			(layer "B.Fab")
		)
		(pad "1" smd rect
			(at 0.5334 0 180)
			(size 0.7112 0.6096)
			(layers "B.Cu" "B.Mask" "B.Paste")
			(net "R_MAC_10MHZ_RF_OUT")
		)
		(pad "2" smd rect
			(at -0.5334 0 180)
			(size 0.7112 0.6096)
			(layers "B.Cu" "B.Mask" "B.Paste")
			(net "FPGA_IN_MAC_10MHZ_OUT")
		)
		(zone
			(layer "B.Cu")
			(hatch none 0.5)
			(connect_pads
				(clearance 0)
			)
			(min_thickness 0.25)
			(keepout
				(tracks allowed)
				(vias not_allowed)
				(pads allowed)
				(copperpour not_allowed)
				(footprints allowed)
			)
			(placement
				(enabled no)
				(sheetname "")
			)
			(fill
				(thermal_gap 0.5)
				(thermal_bridge_width 0.5)
				(island_removal_mode 0)
			)
			(polygon
				(pts
					(xy 124.6632 -46.8122) (xy 124.6632 -47.4218) (xy 124.5108 -47.4218) (xy 124.5108 -46.8122)
				)
			)
		)
		(zone
			(layer "B.Cu")
			(hatch none 0.5)
			(connect_pads
				(clearance 0)
			)
			(min_thickness 0.25)
			(keepout
				(tracks not_allowed)
				(vias allowed)
				(pads allowed)
				(copperpour not_allowed)
				(footprints allowed)
			)
			(placement
				(enabled no)
				(sheetname "")
			)
			(fill
				(thermal_gap 0.5)
				(thermal_bridge_width 0.5)
				(island_removal_mode 0)
			)
			(polygon
				(pts
					(xy 124.6632 -46.8122) (xy 124.6632 -47.4218) (xy 124.5108 -47.4218) (xy 124.5108 -46.8122)
				)
			)
		)
	)
)
